# S9S_MB_2U (Grand Teton) — schematic netlist excerpt (pin names and nets, part order shuffled) for the footprints in the layout excerpt that follows; sources: Cadence DE-HDL packaged netlist, KiCad conversion of 03242023_DA0F0TMBIJ0_F0T_Motherboard_J_brd_V01_OCP.brd

PC192_P0_2  Q_CAP  1UF 16V 10% X6S  pkg C0402  page 275 : A = SW_P12V_PVCCINFAON_CPU0_FLT ; B = GND
C3269  Q_CAP  1000PF 50V 5% EMPTY  pkg 0402  page 266 : A = PWRGD_PVCCFA_EHV_FIVRA_CPU0_R ; B = GND

(kicad_pcb
	(version 20260206)
	(generator "pcbnew")
	(generator_version "10.0")
	(general
		(thickness 1.6)
		(legacy_teardrops no)
	)
	(paper "A4")
	(title_block
		(title "03242023_DA0F0TMBIJ0_F0T_Motherboard_J_brd_V01_OCP.brd")
		(comment 1 "Grand Teton / footprints 1266-1267 of 6105")
	)
	(layers
		(0 "F.Cu" signal "TOP")
		(4 "In1.Cu" signal "GND")
		(6 "In2.Cu" signal "IN1")
		(8 "In3.Cu" signal "GND1")
		(10 "In4.Cu" signal "IN2")
		(12 "In5.Cu" signal "GND2")
		(14 "In6.Cu" signal "IN3")
		(16 "In7.Cu" signal "GND3")
		(18 "In8.Cu" signal "VCC")
		(20 "In9.Cu" signal "VCC1")
		(22 "In10.Cu" signal "GND4")
		(24 "In11.Cu" signal "IN4")
		(26 "In12.Cu" signal "GND5")
		(28 "In13.Cu" signal "IN5")
		(30 "In14.Cu" signal "GND6")
		(32 "In15.Cu" signal "IN6")
		(34 "In16.Cu" signal "GND7")
		(2 "B.Cu" signal "BOTTOM")
		(9 "F.Adhes" user "F.Adhesive")
		(11 "B.Adhes" user "B.Adhesive")
		(13 "F.Paste" user "Package Geometry/Pastemask Top")
		(15 "B.Paste" user "Package Geometry/Pastemask Bottom")
		(5 "F.SilkS" user "Ref Des/Silkscreen Top")
		(7 "B.SilkS" user "Ref Des/Silkscreen Bottom")
		(1 "F.Mask" user "Board Geometry/Soldermask Top")
		(3 "B.Mask" user "Board Geometry/Soldermask Bottom")
		(17 "Dwgs.User" user "User.Drawings")
		(19 "Cmts.User" user "User.Comments")
		(21 "Eco1.User" user "User.Eco1")
		(23 "Eco2.User" user "User.Eco2")
		(25 "Edge.Cuts" user "Board Geometry/Outline")
		(27 "Margin" user)
		(31 "F.CrtYd" user "Package Geometry/Place Bound Top")
		(29 "B.CrtYd" user "Package Geometry/Place Bound Bottom")
		(35 "F.Fab" user "Ref Des/Assembly Top")
		(33 "B.Fab" user "Ref Des/Assembly Bottom")
	)
	(footprint ""
		(layer "F.Cu")
		(at 420.124128 -175.135286 -90)
		(property "Reference" "PC192_P0_2"
			(at 0 0 270)
			(layer "F.SilkS")
			(hide yes)
			(effects
				(font
					(size 1.27 1.27)
				)
			)
		)
		(property "Value" ""
			(at 0 0 270)
			(layer "F.Fab")
			(effects
				(font
					(size 1.27 1.27)
				)
			)
		)
		(duplicate_pad_numbers_are_jumpers no)
		(fp_line
			(start -0.7874 0.4064)
			(end -0.7874 -0.4064)
			(stroke
				(width 0.1524)
				(type default)
			)
			(layer "F.SilkS")
		)
		(fp_line
			(start 0.7874 0.4064)
			(end -0.7874 0.4064)
			(stroke
				(width 0.1524)
				(type default)
			)
			(layer "F.SilkS")
		)
		(fp_line
			(start -0.7874 -0.4064)
			(end 0.7874 -0.4064)
			(stroke
				(width 0.1524)
				(type default)
			)
			(layer "F.SilkS")
		)
		(fp_line
			(start 0.7874 -0.4064)
			(end 0.7874 0.4064)
			(stroke
				(width 0.1524)
				(type default)
			)
			(layer "F.SilkS")
		)
		(fp_line
			(start -0.67945 0.3048)
			(end -0.67945 -0.305054)
			(stroke
				(width 0.1)
				(type default)
			)
			(layer "F.Fab")
		)
		(fp_line
			(start -0.12065 0.3048)
			(end -0.67945 0.3048)
			(stroke
				(width 0.1)
				(type default)
			)
			(layer "F.Fab")
		)
		(fp_line
			(start 0.120396 0.3048)
			(end 0.120396 0.2794)
			(stroke
				(width 0.1)
				(type default)
			)
			(layer "F.Fab")
		)
		(fp_line
			(start 0.67945 0.3048)
			(end 0.120396 0.3048)
			(stroke
				(width 0.1)
				(type default)
			)
			(layer "F.Fab")
		)
		(fp_line
			(start -0.12065 0.2794)
			(end -0.12065 0.3048)
			(stroke
				(width 0.1)
				(type default)
			)
			(layer "F.Fab")
		)
		(fp_line
			(start 0.120396 0.2794)
			(end -0.12065 0.2794)
			(stroke
				(width 0.1)
				(type default)
			)
			(layer "F.Fab")
		)
		(fp_line
			(start -0.12065 -0.2794)
			(end 0.12065 -0.2794)
			(stroke
				(width 0.1)
				(type default)
			)
			(layer "F.Fab")
		)
		(fp_line
			(start 0.12065 -0.2794)
			(end 0.12065 -0.3048)
			(stroke
				(width 0.1)
				(type default)
			)
			(layer "F.Fab")
		)
		(fp_line
			(start 0.12065 -0.3048)
			(end 0.67945 -0.3048)
			(stroke
				(width 0.1)
				(type default)
			)
			(layer "F.Fab")
		)
		(fp_line
			(start 0.67945 -0.3048)
			(end 0.67945 0.3048)
			(stroke
				(width 0.1)
				(type default)
			)
			(layer "F.Fab")
		)
		(fp_line
			(start -0.67945 -0.305054)
			(end -0.12065 -0.305054)
			(stroke
				(width 0.1)
				(type default)
			)
			(layer "F.Fab")
		)
		(fp_line
			(start -0.12065 -0.305054)
			(end -0.12065 -0.2794)
			(stroke
				(width 0.1)
				(type default)
			)
			(layer "F.Fab")
		)
		(pad "1" smd circle
			(at -0.40005 0 270)
			(size 0 0)
			(layers "F.Cu" "F.Mask" "F.Paste")
			(net "SW_P12V_PVCCINFAON_CPU0_FLT")
		)
		(pad "2" smd circle
			(at 0.40005 0 270)
			(size 0 0)
			(layers "F.Cu" "F.Mask" "F.Paste")
			(net "GND")
		)
	)
	(footprint ""
		(layer "F.Cu")
		(at 350.78416 -358.452674 180)
		(property "Reference" "C3269"
			(at 0 0 180)
			(layer "F.SilkS")
			(hide yes)
			(effects
				(font
					(size 1.27 1.27)
				)
			)
		)
		(property "Value" ""
			(at 0 0 180)
			(layer "F.Fab")
			(effects
				(font
					(size 1.27 1.27)
				)
			)
		)
		(duplicate_pad_numbers_are_jumpers no)
		(fp_line
			(start 0.7874 0.4064)
			(end -0.7874 0.4064)
			(stroke
				(width 0.1524)
				(type default)
			)
			(layer "F.SilkS")
		)
		(fp_line
			(start 0.7874 -0.4064)
			(end 0.7874 0.4064)
			(stroke
				(width 0.1524)
				(type default)
			)
			(layer "F.SilkS")
		)
		(fp_line
			(start -0.7874 0.4064)
			(end -0.7874 -0.4064)
			(stroke
				(width 0.1524)
				(type default)
			)
			(layer "F.SilkS")
		)
		(fp_line
			(start -0.7874 -0.4064)
			(end 0.7874 -0.4064)
			(stroke
				(width 0.1524)
				(type default)
			)
			(layer "F.SilkS")
		)
		(fp_line
			(start 0.67945 0.3048)
			(end 0.120396 0.3048)
			(stroke
				(width 0.1)
				(type default)
			)
			(layer "F.Fab")
		)
		(fp_line
			(start 0.67945 -0.3048)
			(end 0.67945 0.3048)
			(stroke
				(width 0.1)
				(type default)
			)
			(layer "F.Fab")
		)
		(fp_line
			(start 0.12065 -0.2794)
			(end 0.12065 -0.3048)
			(stroke
				(width 0.1)
				(type default)
			)
			(layer "F.Fab")
		)
		(fp_line
			(start 0.12065 -0.3048)
			(end 0.67945 -0.3048)
			(stroke
				(width 0.1)
				(type default)
			)
			(layer "F.Fab")
		)
		(fp_line
			(start 0.120396 0.3048)
			(end 0.120396 0.2794)
			(stroke
				(width 0.1)
				(type default)
			)
			(layer "F.Fab")
		)
		(fp_line
			(start 0.120396 0.2794)
			(end -0.12065 0.2794)
			(stroke
				(width 0.1)
				(type default)
			)
			(layer "F.Fab")
		)
		(fp_line
			(start -0.12065 0.3048)
			(end -0.67945 0.3048)
			(stroke
				(width 0.1)
				(type default)
			)
			(layer "F.Fab")
		)
		(fp_line
			(start -0.12065 0.2794)
			(end -0.12065 0.3048)
			(stroke
				(width 0.1)
				(type default)
			)
			(layer "F.Fab")
		)
		(fp_line
			(start -0.12065 -0.2794)
			(end 0.12065 -0.2794)
			(stroke
				(width 0.1)
				(type default)
			)
			(layer "F.Fab")
		)
		(fp_line
			(start -0.12065 -0.305054)
			(end -0.12065 -0.2794)
			(stroke
				(width 0.1)
				(type default)
			)
			(layer "F.Fab")
		)
		(fp_line
			(start -0.67945 0.3048)
			(end -0.67945 -0.305054)
			(stroke
				(width 0.1)
				(type default)
			)
			(layer "F.Fab")
		)
		(fp_line
			(start -0.67945 -0.305054)
			(end -0.12065 -0.305054)
			(stroke
				(width 0.1)
				(type default)
			)
			(layer "F.Fab")
		)
		(pad "1" smd circle
			(at -0.40005 0 180)
			(size 0 0)
			(layers "F.Cu" "F.Mask" "F.Paste")
			(net "PWRGD_PVCCFA_EHV_FIVRA_CPU0_R")
		)
		(pad "2" smd circle
			(at 0.40005 0 180)
			(size 0 0)
			(layers "F.Cu" "F.Mask" "F.Paste")
			(net "GND")
		)
	)
)
